(kicad_pcb
	(version 20211014)
	(generator pcbnew)
	(general
    (thickness 1.6)
  )
	(paper "A4")
	(title_block
    (title "SI test board")
    (rev "1.0.1")
    (company "Antmicro")
		(comment 9 "footprints 24-27 of 27")
	)
	(layers
    (0 "F.Cu" signal)
    (1 "In1.Cu" signal)
    (2 "In2.Cu" signal)
    (31 "B.Cu" signal)
    (32 "B.Adhes" user "B.Adhesive")
    (33 "F.Adhes" user "F.Adhesive")
    (34 "B.Paste" user)
    (35 "F.Paste" user)
    (36 "B.SilkS" user "B.Silkscreen")
    (37 "F.SilkS" user "F.Silkscreen")
    (38 "B.Mask" user)
    (39 "F.Mask" user)
    (40 "Dwgs.User" user "User.Drawings")
    (41 "Cmts.User" user "User.Comments")
    (42 "Eco1.User" user "User.Eco1")
    (43 "Eco2.User" user "User.Eco2")
    (44 "Edge.Cuts" user)
    (45 "Margin" user)
    (46 "B.CrtYd" user "B.Courtyard")
    (47 "F.CrtYd" user "F.Courtyard")
    (48 "B.Fab" user)
    (49 "F.Fab" user)
  )
	(footprint "si-simulation-test-board-footprints:RF_SMA_BoardEdge_RF2-143-T-17-50-G" (layer "F.Cu")
    (tedit 64FEFFC5)
    (at 114.0005 49.22)
    (descr "RF SMA SMD board edge connector")
    (property "Author" "Antmicro")
    (property "License" "Apache-2.0")
    (property "MPN" "RF2-143-T-17-50-G")
    (property "Manufacturer" "ADAM TECH")
    (property "Sheetfile" "si-simulation-test-board.kicad_sch")
    (property "Sheetname" "")
    (attr smd)
    (fp_text reference "J21" (at -4.5 6.88 90) (layer "F.SilkS")
      (effects (font (size 0.7 0.7) (thickness 0.15)) (justify left bottom))
    )
    (fp_text value "Conn_SMA_RF2-143-T-17-50-G" (at 0 9.24) (layer "F.Fab")
      (effects (font (size 0.7 0.7) (thickness 0.15)) (justify left bottom))
    )
    (fp_text user "${REFERENCE}" (at -4.5 13.64) (layer "F.Fab") hide
      (effects (font (size 0.7 0.7) (thickness 0.15)) (justify left bottom))
    )
    (fp_text user "License: Apache-2.0" (at -4.5 12.44) (layer "F.Fab") hide
      (effects (font (size 0.7 0.7) (thickness 0.15)) (justify left bottom))
    )
    (fp_text user "Author: Antmicro" (at -4.5 11.24) (layer "F.Fab") hide
      (effects (font (size 0.7 0.7) (thickness 0.15)) (justify left bottom))
    )
    (fp_rect (start -3.995 -7.53) (end 3.995 7.53) (layer "B.CrtYd") (width 0.05) (fill none))
    (fp_rect (start -3.995 -7.53) (end 3.995 7.53) (layer "F.CrtYd") (width 0.05) (fill none))
    (fp_line (start 0.38 2.654) (end 0.375 6.455) (layer "F.Fab") (width 0.15))
    (fp_line (start 3.174 2.654) (end -3.15 2.654) (layer "F.Fab") (width 0.15))
    (fp_line (start 3.174 1.504) (end -3.174 1.504) (layer "F.Fab") (width 0.15))
    (fp_line (start 2.65 -6.375) (end -2.65 -6.375) (layer "F.Fab") (width 0.15))
    (fp_line (start 0.375 6.455) (end -0.38 6.455) (layer "F.Fab") (width 0.15))
    (fp_line (start -0.38 2.654) (end -0.38 6.455) (layer "F.Fab") (width 0.15))
    (fp_line (start -2.375 6.455) (end -3.174 6.455) (layer "F.Fab") (width 0.15))
    (fp_line (start -3.174 6.455) (end -3.174 1.504) (layer "F.Fab") (width 0.15))
    (fp_line (start -2.65 -6.375) (end -2.65 1.504) (layer "F.Fab") (width 0.15))
    (fp_line (start 2.375 6.455) (end 2.375 2.678) (layer "F.Fab") (width 0.15))
    (fp_line (start -2.375 2.678) (end -2.375 6.455) (layer "F.Fab") (width 0.15))
    (fp_line (start 2.65 -6.375) (end 2.65 1.504) (layer "F.Fab") (width 0.15))
    (fp_line (start 3.174 6.455) (end 3.174 1.504) (layer "F.Fab") (width 0.15))
    (fp_line (start 3.174 6.455) (end 2.375 6.455) (layer "F.Fab") (width 0.15))
    (pad "1" smd rect (at 0.007 4.955) (size 2.29 4.191) (layers "F.Cu" "F.Paste" "F.Mask")
      (net 12 "unconnected-(J21-Pad1)") (pinfunction "1") (pintype "passive+no_connect"))
    (pad "2" smd rect (at 2.975 4.955) (size 1.45 4.191) (layers "B.Cu" "B.Paste" "B.Mask")
      (net 2 "GND") (pinfunction "2") (pintype "passive"))
    (pad "2" smd rect (at -2.975 4.955) (size 1.45 4.191) (layers "F.Cu" "F.Paste" "F.Mask")
      (net 2 "GND") (pinfunction "2") (pintype "passive"))
    (pad "2" smd rect (at 2.975 4.955) (size 1.45 4.191) (layers "F.Cu" "F.Paste" "F.Mask")
      (net 2 "GND") (pinfunction "2") (pintype "passive"))
    (pad "2" smd rect (at -2.975 4.955) (size 1.45 4.191) (layers "B.Cu" "B.Paste" "B.Mask")
      (net 2 "GND") (pinfunction "2") (pintype "passive"))
  )
	(footprint "si-simulation-test-board-footprints:RF_SMA_BoardEdge_RF2-143-T-17-50-G" (layer "F.Cu")
    (tedit 64FEFFC5)
    (at 124.0505 49.27)
    (descr "RF SMA SMD board edge connector")
    (property "Author" "Antmicro")
    (property "License" "Apache-2.0")
    (property "MPN" "RF2-143-T-17-50-G")
    (property "Manufacturer" "ADAM TECH")
    (property "Sheetfile" "si-simulation-test-board.kicad_sch")
    (property "Sheetname" "")
    (attr smd)
    (fp_text reference "J22" (at -4.5 6.88 90) (layer "F.SilkS")
      (effects (font (size 0.7 0.7) (thickness 0.15)) (justify left bottom))
    )
    (fp_text value "Conn_SMA_RF2-143-T-17-50-G" (at 0 9.24) (layer "F.Fab")
      (effects (font (size 0.7 0.7) (thickness 0.15)) (justify left bottom))
    )
    (fp_text user "Author: Antmicro" (at -4.5 11.24) (layer "F.Fab") hide
      (effects (font (size 0.7 0.7) (thickness 0.15)) (justify left bottom))
    )
    (fp_text user "License: Apache-2.0" (at -4.5 12.44) (layer "F.Fab") hide
      (effects (font (size 0.7 0.7) (thickness 0.15)) (justify left bottom))
    )
    (fp_text user "${REFERENCE}" (at -4.5 13.64) (layer "F.Fab") hide
      (effects (font (size 0.7 0.7) (thickness 0.15)) (justify left bottom))
    )
    (fp_rect (start -3.995 -7.53) (end 3.995 7.53) (layer "B.CrtYd") (width 0.05) (fill none))
    (fp_rect (start -3.995 -7.53) (end 3.995 7.53) (layer "F.CrtYd") (width 0.05) (fill none))
    (fp_line (start -2.375 2.678) (end -2.375 6.455) (layer "F.Fab") (width 0.15))
    (fp_line (start -2.375 6.455) (end -3.174 6.455) (layer "F.Fab") (width 0.15))
    (fp_line (start 0.375 6.455) (end -0.38 6.455) (layer "F.Fab") (width 0.15))
    (fp_line (start -2.65 -6.375) (end -2.65 1.504) (layer "F.Fab") (width 0.15))
    (fp_line (start 3.174 2.654) (end -3.15 2.654) (layer "F.Fab") (width 0.15))
    (fp_line (start -3.174 6.455) (end -3.174 1.504) (layer "F.Fab") (width 0.15))
    (fp_line (start 3.174 6.455) (end 2.375 6.455) (layer "F.Fab") (width 0.15))
    (fp_line (start 0.38 2.654) (end 0.375 6.455) (layer "F.Fab") (width 0.15))
    (fp_line (start 2.375 6.455) (end 2.375 2.678) (layer "F.Fab") (width 0.15))
    (fp_line (start -0.38 2.654) (end -0.38 6.455) (layer "F.Fab") (width 0.15))
    (fp_line (start 3.174 6.455) (end 3.174 1.504) (layer "F.Fab") (width 0.15))
    (fp_line (start 2.65 -6.375) (end 2.65 1.504) (layer "F.Fab") (width 0.15))
    (fp_line (start 3.174 1.504) (end -3.174 1.504) (layer "F.Fab") (width 0.15))
    (fp_line (start 2.65 -6.375) (end -2.65 -6.375) (layer "F.Fab") (width 0.15))
    (pad "1" smd rect (at 0.007 4.955) (size 2.29 4.191) (layers "F.Cu" "F.Paste" "F.Mask")
      (net 13 "unconnected-(J22-Pad1)") (pinfunction "1") (pintype "passive+no_connect"))
    (pad "2" smd rect (at -2.975 4.955) (size 1.45 4.191) (layers "B.Cu" "B.Paste" "B.Mask")
      (net 2 "GND") (pinfunction "2") (pintype "passive"))
    (pad "2" smd rect (at 2.975 4.955) (size 1.45 4.191) (layers "F.Cu" "F.Paste" "F.Mask")
      (net 2 "GND") (pinfunction "2") (pintype "passive"))
    (pad "2" smd rect (at 2.975 4.955) (size 1.45 4.191) (layers "B.Cu" "B.Paste" "B.Mask")
      (net 2 "GND") (pinfunction "2") (pintype "passive"))
    (pad "2" smd rect (at -2.975 4.955) (size 1.45 4.191) (layers "F.Cu" "F.Paste" "F.Mask")
      (net 2 "GND") (pinfunction "2") (pintype "passive"))
  )
	(footprint "si-simulation-test-board-footprints:RF_SMA_BoardEdge_RF2-143-T-17-50-G" (layer "F.Cu")
    (tedit 64FEFFC5)
    (at 91.37 85.999499 90)
    (descr "RF SMA SMD board edge connector")
    (property "Author" "Antmicro")
    (property "License" "Apache-2.0")
    (property "MPN" "RF2-143-T-17-50-G")
    (property "Manufacturer" "ADAM TECH")
    (property "Sheetfile" "si-simulation-test-board.kicad_sch")
    (property "Sheetname" "")
    (attr smd)
    (fp_text reference "J7" (at -4.5 6.88 180) (layer "F.SilkS")
      (effects (font (size 0.7 0.7) (thickness 0.15)) (justify left bottom))
    )
    (fp_text value "Conn_SMA_RF2-143-T-17-50-G" (at 0 9.24 90) (layer "F.Fab")
      (effects (font (size 0.7 0.7) (thickness 0.15)) (justify left bottom))
    )
    (fp_text user "License: Apache-2.0" (at -4.5 12.44 90) (layer "F.Fab") hide
      (effects (font (size 0.7 0.7) (thickness 0.15)) (justify left bottom))
    )
    (fp_text user "Author: Antmicro" (at -4.5 11.24 90) (layer "F.Fab") hide
      (effects (font (size 0.7 0.7) (thickness 0.15)) (justify left bottom))
    )
    (fp_text user "${REFERENCE}" (at -4.5 13.64 90) (layer "F.Fab") hide
      (effects (font (size 0.7 0.7) (thickness 0.15)) (justify left bottom))
    )
    (fp_rect (start -3.995 -7.53) (end 3.995 7.53) (layer "B.CrtYd") (width 0.05) (fill none))
    (fp_rect (start -3.995 -7.53) (end 3.995 7.53) (layer "F.CrtYd") (width 0.05) (fill none))
    (fp_line (start 3.174 6.455) (end 2.375 6.455) (layer "F.Fab") (width 0.15))
    (fp_line (start 2.65 -6.375) (end 2.65 1.504) (layer "F.Fab") (width 0.15))
    (fp_line (start 3.174 2.654) (end -3.15 2.654) (layer "F.Fab") (width 0.15))
    (fp_line (start -2.375 6.455) (end -3.174 6.455) (layer "F.Fab") (width 0.15))
    (fp_line (start -3.174 6.455) (end -3.174 1.504) (layer "F.Fab") (width 0.15))
    (fp_line (start -2.375 2.678) (end -2.375 6.455) (layer "F.Fab") (width 0.15))
    (fp_line (start 2.65 -6.375) (end -2.65 -6.375) (layer "F.Fab") (width 0.15))
    (fp_line (start 3.174 1.504) (end -3.174 1.504) (layer "F.Fab") (width 0.15))
    (fp_line (start -0.38 2.654) (end -0.38 6.455) (layer "F.Fab") (width 0.15))
    (fp_line (start 2.375 6.455) (end 2.375 2.678) (layer "F.Fab") (width 0.15))
    (fp_line (start 0.375 6.455) (end -0.38 6.455) (layer "F.Fab") (width 0.15))
    (fp_line (start 0.38 2.654) (end 0.375 6.455) (layer "F.Fab") (width 0.15))
    (fp_line (start 3.174 6.455) (end 3.174 1.504) (layer "F.Fab") (width 0.15))
    (fp_line (start -2.65 -6.375) (end -2.65 1.504) (layer "F.Fab") (width 0.15))
    (pad "1" smd rect (at 0.007 4.955 90) (size 2.29 4.191) (layers "F.Cu" "F.Paste" "F.Mask")
      (net 5 "Net-(J7-Pad1)") (pinfunction "1") (pintype "passive"))
    (pad "2" smd rect (at -2.975 4.955 90) (size 1.45 4.191) (layers "B.Cu" "B.Paste" "B.Mask")
      (net 2 "GND") (pinfunction "2") (pintype "passive"))
    (pad "2" smd rect (at 2.975 4.955 90) (size 1.45 4.191) (layers "B.Cu" "B.Paste" "B.Mask")
      (net 2 "GND") (pinfunction "2") (pintype "passive"))
    (pad "2" smd rect (at -2.975 4.955 90) (size 1.45 4.191) (layers "F.Cu" "F.Paste" "F.Mask")
      (net 2 "GND") (pinfunction "2") (pintype "passive"))
    (pad "2" smd rect (at 2.975 4.955 90) (size 1.45 4.191) (layers "F.Cu" "F.Paste" "F.Mask")
      (net 2 "GND") (pinfunction "2") (pintype "passive"))
  )
	(footprint "si-simulation-test-board-footprints:R_0201" (layer "F.Cu")
    (tedit 5FBD1D44)
    (at 128.744001 88.992501 180)
    (descr "Resistor SMD 0201")
    (tags "resistor SMD 0201")
    (property "Author" "Antmicro")
    (property "DNP" "DNP")
    (property "License" "Apache-2.0")
    (property "MPN" "CR0201-FX-0R00GLF")
    (property "Manufacturer" "Bourns")
    (property "Sheetfile" "si-simulation-test-board.kicad_sch")
    (property "Sheetname" "")
    (property "Tolerance" "1%")
    (property "Val" "0R")
    (attr smd)
    (fp_text reference "R3" (at 0 -0.5) (layer "F.SilkS") hide
      (effects (font (size 0.7 0.7) (thickness 0.15)) (justify right bottom))
    )
    (fp_text value "R_0R_0201" (at 0 1.25) (layer "F.Fab")
      (effects (font (size 0.7 0.7) (thickness 0.15)) (justify right bottom))
    )
    (fp_text user "Author: Antmicro" (at -0.71 5.25) (layer "F.Fab") hide
      (effects (font (size 0.7 0.7) (thickness 0.15)) (justify right bottom))
    )
    (fp_text user "License: Apache-2.0" (at -0.71 4.25) (layer "F.Fab") hide
      (effects (font (size 0.7 0.7) (thickness 0.15)) (justify right bottom))
    )
    (fp_text user "${REFERENCE}" (at -0.71 3.25) (layer "F.Fab") hide
      (effects (font (size 0.7 0.7) (thickness 0.15)) (justify right bottom))
    )
    (fp_rect (start -0.71 -0.36) (end 0.71 0.36) (layer "F.CrtYd") (width 0.05) (fill none))
    (fp_rect (start -0.3 -0.15) (end 0.298 0.148) (layer "F.Fab") (width 0.15) (fill none))
    (pad "" smd roundrect (at 0.344 0 180) (size 0.318 0.36) (layers "F.Paste") (roundrect_rratio 0.25))
    (pad "" smd roundrect (at -0.346 0 180) (size 0.318 0.36) (layers "F.Paste") (roundrect_rratio 0.25))
    (pad "1" smd roundrect (at -0.32 0 180) (size 0.46 0.4) (layers "F.Cu" "F.Mask") (roundrect_rratio 0.25)
      (net 2 "GND") (pintype "passive"))
    (pad "2" smd roundrect (at 0.32 0 180) (size 0.46 0.4) (layers "F.Cu" "F.Mask") (roundrect_rratio 0.25)
      (net 5 "Net-(J7-Pad1)") (pintype "passive"))
  )
)
